# BASEBOARD_FAB2 (Tioga Pass) — schematic netlist excerpt (pin names and nets, part order shuffled) for the footprints in the layout excerpt that follows; sources: Cadence DE-HDL packaged netlist, KiCad conversion of Wiwynn_Tioga_Pass_MB.brd

C1W21  CAP  0.033UF 50V 10% X7R  pkg 0603LF  page 146 : A = A_USB2AVRES ; B = GND
C3T14  CAP  10UF 16V 10% X6S  pkg 0805  page 231 : A = VR_FET_SW_P12V_STBY_PVPP_ABC ; B = GND
C2U9  CAP  0.22UF 16V 10% X7R  pkg 0402  page 107 : A = P3E_CPU0_PE1_PCH_RXP<3> ; B = P3E_CPU0_PE1_SS_RXP<3>

(kicad_pcb
	(version 20260206)
	(generator "pcbnew")
	(generator_version "10.0")
	(general
		(thickness 1.6)
		(legacy_teardrops no)
	)
	(paper "A4")
	(title_block
		(title "Wiwynn_Tioga_Pass_MB.brd")
		(comment 1 "Tioga Pass / footprints 3174-3176 of 4770")
	)
	(layers
		(0 "F.Cu" signal "TOP")
		(4 "In1.Cu" signal "L2GND")
		(6 "In2.Cu" signal "L3")
		(8 "In3.Cu" signal "L4GND")
		(10 "In4.Cu" signal "L5")
		(12 "In5.Cu" signal "L6GND")
		(14 "In6.Cu" signal "L7VCC")
		(16 "In7.Cu" signal "L8VCC")
		(18 "In8.Cu" signal "L9GND")
		(20 "In9.Cu" signal "L10")
		(22 "In10.Cu" signal "L11GND")
		(24 "In11.Cu" signal "L12")
		(26 "In12.Cu" signal "L13GND")
		(2 "B.Cu" signal "BOTTOM")
		(9 "F.Adhes" user "F.Adhesive")
		(11 "B.Adhes" user "B.Adhesive")
		(13 "F.Paste" user "Package Geometry/Pastemask Top")
		(15 "B.Paste" user "Package Geometry/Pastemask Bottom")
		(5 "F.SilkS" user "Ref Des/Silkscreen Top")
		(7 "B.SilkS" user "Ref Des/Silkscreen Bottom")
		(1 "F.Mask" user "Board Geometry/Soldermask Top")
		(3 "B.Mask" user "Board Geometry/Soldermask Bottom")
		(17 "Dwgs.User" user "User.Drawings")
		(19 "Cmts.User" user "User.Comments")
		(21 "Eco1.User" user "User.Eco1")
		(23 "Eco2.User" user "User.Eco2")
		(25 "Edge.Cuts" user "Board Geometry/Outline")
		(27 "Margin" user)
		(31 "F.CrtYd" user "Package Geometry/Place Bound Top")
		(29 "B.CrtYd" user "Package Geometry/Place Bound Bottom")
		(35 "F.Fab" user "Ref Des/Assembly Top")
		(33 "B.Fab" user "Ref Des/Assembly Bottom")
	)
	(footprint ""
		(layer "B.Cu")
		(at 407.416 -31.6865 -90)
		(property "Reference" "C1W21"
			(at -0.97536 0.76708 0)
			(unlocked yes)
			(layer "B.SilkS")
			(effects
				(font
					(size 0.4064 0.254)
					(thickness 0.1524)
				)
				(justify mirror)
			)
		)
		(property "Value" ""
			(at 0 0 90)
			(layer "B.Fab")
			(effects
				(font
					(size 1.27 1.27)
				)
				(justify mirror)
			)
		)
		(duplicate_pad_numbers_are_jumpers no)
		(fp_poly
			(pts
				(xy 0.4953 -0.2032) (xy -0.4953 -0.2032) (xy -0.4953 1.6002) (xy 0.4953 1.6002)
			)
			(stroke
				(width 0)
				(type default)
			)
			(fill no)
			(layer "B.CrtYd")
		)
		(fp_line
			(start -0.4953 1.6002)
			(end 0.4953 1.6002)
			(stroke
				(width 0.1)
				(type default)
			)
			(layer "B.Fab")
		)
		(fp_line
			(start 0.4953 1.6002)
			(end 0.4953 -0.2032)
			(stroke
				(width 0.1)
				(type default)
			)
			(layer "B.Fab")
		)
		(fp_line
			(start -0.4953 -0.2032)
			(end -0.4953 1.6002)
			(stroke
				(width 0.1)
				(type default)
			)
			(layer "B.Fab")
		)
		(fp_line
			(start 0.4953 -0.2032)
			(end -0.4953 -0.2032)
			(stroke
				(width 0.1)
				(type default)
			)
			(layer "B.Fab")
		)
		(pad "1" smd rect
			(at 0 0 90)
			(size 0.762 0.889)
			(layers "B.Cu" "B.Mask" "B.Paste")
			(net "A_USB2AVRES")
		)
		(pad "2" smd rect
			(at 0 1.397 90)
			(size 0.762 0.889)
			(layers "B.Cu" "B.Mask" "B.Paste")
			(net "GND")
		)
		(zone
			(layer "B.Cu")
			(hatch none 0.5)
			(connect_pads
				(clearance 0)
			)
			(min_thickness 0.25)
			(keepout
				(tracks not_allowed)
				(vias allowed)
				(pads allowed)
				(copperpour not_allowed)
				(footprints allowed)
			)
			(placement
				(enabled no)
				(sheetname "")
			)
			(fill
				(thermal_gap 0.5)
				(thermal_bridge_width 0.5)
				(island_removal_mode 0)
			)
			(polygon
				(pts
					(xy 406.9715 -31.3055) (xy 406.9715 -32.0675) (xy 406.4635 -32.0675) (xy 406.4635 -31.3055)
				)
			)
		)
	)
	(footprint ""
		(layer "B.Cu")
		(at 341.728806 -61.257434)
		(property "Reference" "C2U9"
			(at 0 0 0)
			(layer "B.SilkS")
			(hide yes)
			(effects
				(font
					(size 1.27 1.27)
				)
				(justify mirror)
			)
		)
		(property "Value" ""
			(at 0 0 0)
			(layer "B.Fab")
			(effects
				(font
					(size 1.27 1.27)
				)
				(justify mirror)
			)
		)
		(duplicate_pad_numbers_are_jumpers no)
		(fp_poly
			(pts
				(xy -0.3048 -0.1016) (xy -0.3048 0.9906) (xy 0.3048 0.9906) (xy 0.3048 -0.1016)
			)
			(stroke
				(width 0)
				(type default)
			)
			(fill no)
			(layer "B.CrtYd")
		)
		(fp_line
			(start -0.3048 -0.1016)
			(end 0.3048 -0.1016)
			(stroke
				(width 0.1)
				(type default)
			)
			(layer "B.Fab")
		)
		(fp_line
			(start -0.3048 0.9906)
			(end -0.3048 -0.1016)
			(stroke
				(width 0.1)
				(type default)
			)
			(layer "B.Fab")
		)
		(fp_line
			(start 0.3048 -0.1016)
			(end 0.3048 0.9906)
			(stroke
				(width 0.1)
				(type default)
			)
			(layer "B.Fab")
		)
		(fp_line
			(start 0.3048 0.9906)
			(end -0.3048 0.9906)
			(stroke
				(width 0.1)
				(type default)
			)
			(layer "B.Fab")
		)
		(pad "1" smd rect
			(at 0 0 180)
			(size 0.508 0.508)
			(layers "B.Cu" "B.Mask" "B.Paste")
			(net "P3E_CPU0_PE1_PCH_RXP<3>")
		)
		(pad "2" smd rect
			(at 0 0.889 180)
			(size 0.508 0.508)
			(layers "B.Cu" "B.Mask" "B.Paste")
			(net "P3E_CPU0_PE1_SS_RXP<3>")
		)
		(zone
			(layer "B.Cu")
			(hatch none 0.5)
			(connect_pads
				(clearance 0)
			)
			(min_thickness 0.25)
			(keepout
				(tracks allowed)
				(vias not_allowed)
				(pads allowed)
				(copperpour not_allowed)
				(footprints allowed)
			)
			(placement
				(enabled no)
				(sheetname "")
			)
			(fill
				(thermal_gap 0.5)
				(thermal_bridge_width 0.5)
				(island_removal_mode 0)
			)
			(polygon
				(pts
					(xy 341.982806 -61.003434) (xy 341.474806 -61.003434) (xy 341.474806 -60.622434) (xy 341.982806 -60.622434)
				)
			)
		)
		(zone
			(layer "B.Cu")
			(hatch none 0.5)
			(connect_pads
				(clearance 0)
			)
			(min_thickness 0.25)
			(keepout
				(tracks not_allowed)
				(vias allowed)
				(pads allowed)
				(copperpour not_allowed)
				(footprints allowed)
			)
			(placement
				(enabled no)
				(sheetname "")
			)
			(fill
				(thermal_gap 0.5)
				(thermal_bridge_width 0.5)
				(island_removal_mode 0)
			)
			(polygon
				(pts
					(xy 341.982806 -60.622434) (xy 341.474806 -60.622434) (xy 341.474806 -61.003434) (xy 341.982806 -61.003434)
				)
			)
		)
	)
	(footprint ""
		(layer "B.Cu")
		(at 351.416874 -22.949916 90)
		(property "Reference" "C3T14"
			(at -1.47828 0.78994 180)
			(unlocked yes)
			(layer "B.SilkS")
			(effects
				(font
					(size 0.4064 0.254)
					(thickness 0.1524)
				)
				(justify mirror)
			)
		)
		(property "Value" ""
			(at 0 0 90)
			(layer "B.Fab")
			(effects
				(font
					(size 1.27 1.27)
				)
				(justify mirror)
			)
		)
		(duplicate_pad_numbers_are_jumpers no)
		(fp_poly
			(pts
				(xy 0.7239 -0.2159) (xy -0.7239 -0.2159) (xy -0.7239 1.9939) (xy 0.7239 1.9939)
			)
			(stroke
				(width 0)
				(type default)
			)
			(fill no)
			(layer "B.CrtYd")
		)
		(fp_line
			(start 0.7239 -0.2159)
			(end 0.7239 1.9939)
			(stroke
				(width 0.1)
				(type default)
			)
			(layer "B.Fab")
		)
		(fp_line
			(start -0.7239 -0.2159)
			(end 0.7239 -0.2159)
			(stroke
				(width 0.1)
				(type default)
			)
			(layer "B.Fab")
		)
		(fp_line
			(start 0.7239 1.9939)
			(end -0.7239 1.9939)
			(stroke
				(width 0.1)
				(type default)
			)
			(layer "B.Fab")
		)
		(fp_line
			(start -0.7239 1.9939)
			(end -0.7239 -0.2159)
			(stroke
				(width 0.1)
				(type default)
			)
			(layer "B.Fab")
		)
		(pad "1" smd rect
			(at 0 0 270)
			(size 1.27 1.016)
			(layers "B.Cu" "B.Mask" "B.Paste")
			(net "VR_FET_SW_P12V_STBY_PVPP_ABC")
		)
		(pad "2" smd rect
			(at 0 1.778 270)
			(size 1.27 1.016)
			(layers "B.Cu" "B.Mask" "B.Paste")
			(net "GND")
		)
		(zone
			(layer "B.Cu")
			(hatch none 0.5)
			(connect_pads
				(clearance 0)
			)
			(min_thickness 0.25)
			(keepout
				(tracks not_allowed)
				(vias allowed)
				(pads allowed)
				(copperpour not_allowed)
				(footprints allowed)
			)
			(placement
				(enabled no)
				(sheetname "")
			)
			(fill
				(thermal_gap 0.5)
				(thermal_bridge_width 0.5)
				(island_removal_mode 0)
			)
			(polygon
				(pts
					(xy 351.924874 -23.584916) (xy 351.924874 -22.314916) (xy 352.686874 -22.314916) (xy 352.686874 -23.584916)
				)
			)
		)
	)
)
